# S9S_MB_2U (Grand Teton) — schematic netlist excerpt (pin names and nets, part order shuffled) for the footprints in the layout excerpt that follows; sources: Cadence DE-HDL packaged netlist, KiCad conversion of 03242023_DA0F0TMBIJ0_F0T_Motherboard_J_brd_V01_OCP.brd

C825  Q_CAP_DIFFBUS  DIFF BUS_0.22UF 6.3V 20% X6S  pkg C0201  page 175 : \1\ = P5E_CPU1_PE1_TX_C_DP<6> ; \2\ = P5E_CPU1_PE1_TX_DP<6>
PC2139  Q_CAP  1UF 25V 10% X6S  pkg C0402  page 162 : A = P12V_AUX ; B = GND
C736  Q_CAP_DIFFBUS  DIFF BUS_0.22UF 6.3V 20% X6S  pkg C0201  page 176 : \1\ = P5E_CPU1_PE0_TX_C_DN<2> ; \2\ = P5E_CPU1_PE0_TX_DN<2>

(kicad_pcb
	(version 20260206)
	(generator "pcbnew")
	(generator_version "10.0")
	(general
		(thickness 1.6)
		(legacy_teardrops no)
	)
	(paper "A4")
	(title_block
		(title "03242023_DA0F0TMBIJ0_F0T_Motherboard_J_brd_V01_OCP.brd")
		(comment 1 "Grand Teton / footprints 2654-2656 of 6105")
	)
	(layers
		(0 "F.Cu" signal "TOP")
		(4 "In1.Cu" signal "GND")
		(6 "In2.Cu" signal "IN1")
		(8 "In3.Cu" signal "GND1")
		(10 "In4.Cu" signal "IN2")
		(12 "In5.Cu" signal "GND2")
		(14 "In6.Cu" signal "IN3")
		(16 "In7.Cu" signal "GND3")
		(18 "In8.Cu" signal "VCC")
		(20 "In9.Cu" signal "VCC1")
		(22 "In10.Cu" signal "GND4")
		(24 "In11.Cu" signal "IN4")
		(26 "In12.Cu" signal "GND5")
		(28 "In13.Cu" signal "IN5")
		(30 "In14.Cu" signal "GND6")
		(32 "In15.Cu" signal "IN6")
		(34 "In16.Cu" signal "GND7")
		(2 "B.Cu" signal "BOTTOM")
		(9 "F.Adhes" user "F.Adhesive")
		(11 "B.Adhes" user "B.Adhesive")
		(13 "F.Paste" user "Package Geometry/Pastemask Top")
		(15 "B.Paste" user "Package Geometry/Pastemask Bottom")
		(5 "F.SilkS" user "Ref Des/Silkscreen Top")
		(7 "B.SilkS" user "Ref Des/Silkscreen Bottom")
		(1 "F.Mask" user "Board Geometry/Soldermask Top")
		(3 "B.Mask" user "Board Geometry/Soldermask Bottom")
		(17 "Dwgs.User" user "User.Drawings")
		(19 "Cmts.User" user "User.Comments")
		(21 "Eco1.User" user "User.Eco1")
		(23 "Eco2.User" user "User.Eco2")
		(25 "Edge.Cuts" user "Board Geometry/Outline")
		(27 "Margin" user)
		(31 "F.CrtYd" user "Package Geometry/Place Bound Top")
		(29 "B.CrtYd" user "Package Geometry/Place Bound Bottom")
		(35 "F.Fab" user "Ref Des/Assembly Top")
		(33 "B.Fab" user "Ref Des/Assembly Bottom")
	)
	(footprint ""
		(layer "F.Cu")
		(at 41.874694 -17.623536 90)
		(property "Reference" "C825"
			(at 0 0 90)
			(layer "F.SilkS")
			(hide yes)
			(effects
				(font
					(size 1.27 1.27)
				)
			)
		)
		(property "Value" ""
			(at 0 0 90)
			(layer "F.Fab")
			(effects
				(font
					(size 1.27 1.27)
				)
			)
		)
		(duplicate_pad_numbers_are_jumpers no)
		(fp_line
			(start 0.299974 -0.150114)
			(end 0.299974 0.150114)
			(stroke
				(width 0.1)
				(type default)
			)
			(layer "F.Fab")
		)
		(fp_line
			(start -0.299974 -0.150114)
			(end 0.299974 -0.150114)
			(stroke
				(width 0.1)
				(type default)
			)
			(layer "F.Fab")
		)
		(fp_line
			(start 0.299974 0.150114)
			(end -0.299974 0.150114)
			(stroke
				(width 0.1)
				(type default)
			)
			(layer "F.Fab")
		)
		(fp_line
			(start -0.299974 0.150114)
			(end -0.299974 -0.150114)
			(stroke
				(width 0.1)
				(type default)
			)
			(layer "F.Fab")
		)
		(pad "1" smd rect
			(at -0.2667 0 90)
			(size 0.3048 0.381)
			(layers "F.Cu" "F.Mask" "F.Paste")
			(net "P5E_CPU1_PE1_TX_C_DP<6>")
		)
		(pad "2" smd rect
			(at 0.2667 0 90)
			(size 0.3048 0.381)
			(layers "F.Cu" "F.Mask" "F.Paste")
			(net "P5E_CPU1_PE1_TX_DP<6>")
		)
	)
	(footprint ""
		(layer "F.Cu")
		(at 87.776558 -402.371052 -90)
		(property "Reference" "C736"
			(at 0 0 270)
			(layer "F.SilkS")
			(hide yes)
			(effects
				(font
					(size 1.27 1.27)
				)
			)
		)
		(property "Value" ""
			(at 0 0 270)
			(layer "F.Fab")
			(effects
				(font
					(size 1.27 1.27)
				)
			)
		)
		(duplicate_pad_numbers_are_jumpers no)
		(fp_line
			(start -0.299974 0.150114)
			(end -0.299974 -0.150114)
			(stroke
				(width 0.1)
				(type default)
			)
			(layer "F.Fab")
		)
		(fp_line
			(start 0.299974 0.150114)
			(end -0.299974 0.150114)
			(stroke
				(width 0.1)
				(type default)
			)
			(layer "F.Fab")
		)
		(fp_line
			(start -0.299974 -0.150114)
			(end 0.299974 -0.150114)
			(stroke
				(width 0.1)
				(type default)
			)
			(layer "F.Fab")
		)
		(fp_line
			(start 0.299974 -0.150114)
			(end 0.299974 0.150114)
			(stroke
				(width 0.1)
				(type default)
			)
			(layer "F.Fab")
		)
		(pad "1" smd rect
			(at -0.2667 0 270)
			(size 0.3048 0.381)
			(layers "F.Cu" "F.Mask" "F.Paste")
			(net "P5E_CPU1_PE0_TX_C_DN<2>")
		)
		(pad "2" smd rect
			(at 0.2667 0 270)
			(size 0.3048 0.381)
			(layers "F.Cu" "F.Mask" "F.Paste")
			(net "P5E_CPU1_PE0_TX_DN<2>")
		)
	)
	(footprint ""
		(layer "F.Cu")
		(at 76.53401 -24.713946 -90)
		(property "Reference" "PC2139"
			(at 0 0 270)
			(layer "F.SilkS")
			(hide yes)
			(effects
				(font
					(size 1.27 1.27)
				)
			)
		)
		(property "Value" ""
			(at 0 0 270)
			(layer "F.Fab")
			(effects
				(font
					(size 1.27 1.27)
				)
			)
		)
		(duplicate_pad_numbers_are_jumpers no)
		(fp_line
			(start -0.7874 0.4064)
			(end -0.7874 -0.4064)
			(stroke
				(width 0.1524)
				(type default)
			)
			(layer "F.SilkS")
		)
		(fp_line
			(start 0.7874 0.4064)
			(end -0.7874 0.4064)
			(stroke
				(width 0.1524)
				(type default)
			)
			(layer "F.SilkS")
		)
		(fp_line
			(start -0.7874 -0.4064)
			(end 0.7874 -0.4064)
			(stroke
				(width 0.1524)
				(type default)
			)
			(layer "F.SilkS")
		)
		(fp_line
			(start 0.7874 -0.4064)
			(end 0.7874 0.4064)
			(stroke
				(width 0.1524)
				(type default)
			)
			(layer "F.SilkS")
		)
		(fp_line
			(start -0.67945 0.3048)
			(end -0.67945 -0.305054)
			(stroke
				(width 0.1)
				(type default)
			)
			(layer "F.Fab")
		)
		(fp_line
			(start -0.12065 0.3048)
			(end -0.67945 0.3048)
			(stroke
				(width 0.1)
				(type default)
			)
			(layer "F.Fab")
		)
		(fp_line
			(start 0.120396 0.3048)
			(end 0.120396 0.2794)
			(stroke
				(width 0.1)
				(type default)
			)
			(layer "F.Fab")
		)
		(fp_line
			(start 0.67945 0.3048)
			(end 0.120396 0.3048)
			(stroke
				(width 0.1)
				(type default)
			)
			(layer "F.Fab")
		)
		(fp_line
			(start -0.12065 0.2794)
			(end -0.12065 0.3048)
			(stroke
				(width 0.1)
				(type default)
			)
			(layer "F.Fab")
		)
		(fp_line
			(start 0.120396 0.2794)
			(end -0.12065 0.2794)
			(stroke
				(width 0.1)
				(type default)
			)
			(layer "F.Fab")
		)
		(fp_line
			(start -0.12065 -0.2794)
			(end 0.12065 -0.2794)
			(stroke
				(width 0.1)
				(type default)
			)
			(layer "F.Fab")
		)
		(fp_line
			(start 0.12065 -0.2794)
			(end 0.12065 -0.3048)
			(stroke
				(width 0.1)
				(type default)
			)
			(layer "F.Fab")
		)
		(fp_line
			(start 0.12065 -0.3048)
			(end 0.67945 -0.3048)
			(stroke
				(width 0.1)
				(type default)
			)
			(layer "F.Fab")
		)
		(fp_line
			(start 0.67945 -0.3048)
			(end 0.67945 0.3048)
			(stroke
				(width 0.1)
				(type default)
			)
			(layer "F.Fab")
		)
		(fp_line
			(start -0.67945 -0.305054)
			(end -0.12065 -0.305054)
			(stroke
				(width 0.1)
				(type default)
			)
			(layer "F.Fab")
		)
		(fp_line
			(start -0.12065 -0.305054)
			(end -0.12065 -0.2794)
			(stroke
				(width 0.1)
				(type default)
			)
			(layer "F.Fab")
		)
		(pad "1" smd circle
			(at -0.40005 0 270)
			(size 0 0)
			(layers "F.Cu" "F.Mask" "F.Paste")
			(net "P12V_AUX")
		)
		(pad "2" smd circle
			(at 0.40005 0 270)
			(size 0 0)
			(layers "F.Cu" "F.Mask" "F.Paste")
			(net "GND")
		)
	)
)
